# S9S_MB_2U (Grand Teton) — schematic netlist excerpt (pin names and nets, part order shuffled) for the footprints in the layout excerpt that follows; sources: Cadence DE-HDL packaged netlist, KiCad conversion of 03242023_DA0F0TMBIJ0_F0T_Motherboard_J_brd_V01_OCP.brd

R3896  Q_RES  49.9 1% CHIP  pkg 0402LF  page 103 : A = I3C_SPD_DDRABCD_CPU1_LVC1_SCL_5 ; B = I3C_SPD_DDRABCD_CPU1_LVC1_SCL
C559  Q_CAP  0.1UF 25V 10% X7R  pkg 0402  page 235 : A = PVNN_TERM_CPU0 ; B = GND
C371  Q_CAP  47UF 4V 20% X6S  pkg C0805  page 75 : A = PVCCIN_CPU0 ; B = GND

(kicad_pcb
	(version 20260206)
	(generator "pcbnew")
	(generator_version "10.0")
	(general
		(thickness 1.6)
		(legacy_teardrops no)
	)
	(paper "A4")
	(title_block
		(title "03242023_DA0F0TMBIJ0_F0T_Motherboard_J_brd_V01_OCP.brd")
		(comment 1 "Grand Teton / footprints 4562-4564 of 6105")
	)
	(layers
		(0 "F.Cu" signal "TOP")
		(4 "In1.Cu" signal "GND")
		(6 "In2.Cu" signal "IN1")
		(8 "In3.Cu" signal "GND1")
		(10 "In4.Cu" signal "IN2")
		(12 "In5.Cu" signal "GND2")
		(14 "In6.Cu" signal "IN3")
		(16 "In7.Cu" signal "GND3")
		(18 "In8.Cu" signal "VCC")
		(20 "In9.Cu" signal "VCC1")
		(22 "In10.Cu" signal "GND4")
		(24 "In11.Cu" signal "IN4")
		(26 "In12.Cu" signal "GND5")
		(28 "In13.Cu" signal "IN5")
		(30 "In14.Cu" signal "GND6")
		(32 "In15.Cu" signal "IN6")
		(34 "In16.Cu" signal "GND7")
		(2 "B.Cu" signal "BOTTOM")
		(9 "F.Adhes" user "F.Adhesive")
		(11 "B.Adhes" user "B.Adhesive")
		(13 "F.Paste" user "Package Geometry/Pastemask Top")
		(15 "B.Paste" user "Package Geometry/Pastemask Bottom")
		(5 "F.SilkS" user "Ref Des/Silkscreen Top")
		(7 "B.SilkS" user "Ref Des/Silkscreen Bottom")
		(1 "F.Mask" user "Board Geometry/Soldermask Top")
		(3 "B.Mask" user "Board Geometry/Soldermask Bottom")
		(17 "Dwgs.User" user "User.Drawings")
		(19 "Cmts.User" user "User.Comments")
		(21 "Eco1.User" user "User.Eco1")
		(23 "Eco2.User" user "User.Eco2")
		(25 "Edge.Cuts" user "Board Geometry/Outline")
		(27 "Margin" user)
		(31 "F.CrtYd" user "Package Geometry/Place Bound Top")
		(29 "B.CrtYd" user "Package Geometry/Place Bound Bottom")
		(35 "F.Fab" user "Ref Des/Assembly Top")
		(33 "B.Fab" user "Ref Des/Assembly Bottom")
	)
	(footprint ""
		(layer "B.Cu")
		(at 371.273578 -189.56147 180)
		(property "Reference" "C559"
			(at 0 0 0)
			(layer "B.SilkS")
			(hide yes)
			(effects
				(font
					(size 1.27 1.27)
				)
				(justify mirror)
			)
		)
		(property "Value" ""
			(at 0 0 0)
			(layer "B.Fab")
			(effects
				(font
					(size 1.27 1.27)
				)
				(justify mirror)
			)
		)
		(duplicate_pad_numbers_are_jumpers no)
		(fp_line
			(start 0.7874 0.4064)
			(end 0.7874 -0.4064)
			(stroke
				(width 0.1524)
				(type default)
			)
			(layer "B.SilkS")
		)
		(fp_line
			(start 0.7874 -0.4064)
			(end -0.7874 -0.4064)
			(stroke
				(width 0.1524)
				(type default)
			)
			(layer "B.SilkS")
		)
		(fp_line
			(start -0.7874 0.4064)
			(end 0.7874 0.4064)
			(stroke
				(width 0.1524)
				(type default)
			)
			(layer "B.SilkS")
		)
		(fp_line
			(start -0.7874 -0.4064)
			(end -0.7874 0.4064)
			(stroke
				(width 0.1524)
				(type default)
			)
			(layer "B.SilkS")
		)
		(fp_line
			(start 0.67945 0.3048)
			(end 0.67945 -0.305054)
			(stroke
				(width 0.1)
				(type default)
			)
			(layer "B.Fab")
		)
		(fp_line
			(start 0.67945 -0.305054)
			(end 0.12065 -0.305054)
			(stroke
				(width 0.1)
				(type default)
			)
			(layer "B.Fab")
		)
		(fp_line
			(start 0.12065 0.3048)
			(end 0.67945 0.3048)
			(stroke
				(width 0.1)
				(type default)
			)
			(layer "B.Fab")
		)
		(fp_line
			(start 0.12065 0.2794)
			(end 0.12065 0.3048)
			(stroke
				(width 0.1)
				(type default)
			)
			(layer "B.Fab")
		)
		(fp_line
			(start 0.12065 -0.2794)
			(end -0.12065 -0.2794)
			(stroke
				(width 0.1)
				(type default)
			)
			(layer "B.Fab")
		)
		(fp_line
			(start 0.12065 -0.305054)
			(end 0.12065 -0.2794)
			(stroke
				(width 0.1)
				(type default)
			)
			(layer "B.Fab")
		)
		(fp_line
			(start -0.120396 0.3048)
			(end -0.120396 0.2794)
			(stroke
				(width 0.1)
				(type default)
			)
			(layer "B.Fab")
		)
		(fp_line
			(start -0.120396 0.2794)
			(end 0.12065 0.2794)
			(stroke
				(width 0.1)
				(type default)
			)
			(layer "B.Fab")
		)
		(fp_line
			(start -0.12065 -0.2794)
			(end -0.12065 -0.3048)
			(stroke
				(width 0.1)
				(type default)
			)
			(layer "B.Fab")
		)
		(fp_line
			(start -0.12065 -0.3048)
			(end -0.67945 -0.3048)
			(stroke
				(width 0.1)
				(type default)
			)
			(layer "B.Fab")
		)
		(fp_line
			(start -0.67945 0.3048)
			(end -0.120396 0.3048)
			(stroke
				(width 0.1)
				(type default)
			)
			(layer "B.Fab")
		)
		(fp_line
			(start -0.67945 -0.3048)
			(end -0.67945 0.3048)
			(stroke
				(width 0.1)
				(type default)
			)
			(layer "B.Fab")
		)
		(pad "1" smd circle
			(at 0.40005 0)
			(size 0 0)
			(layers "B.Cu" "B.Mask" "B.Paste")
			(net "PVNN_TERM_CPU0")
		)
		(pad "2" smd circle
			(at -0.40005 0)
			(size 0 0)
			(layers "B.Cu" "B.Mask" "B.Paste")
			(net "GND")
		)
	)
	(footprint ""
		(layer "B.Cu")
		(at 30.784546 -317.626746 180)
		(property "Reference" "R3896"
			(at 0 0 0)
			(layer "B.SilkS")
			(hide yes)
			(effects
				(font
					(size 1.27 1.27)
				)
				(justify mirror)
			)
		)
		(property "Value" ""
			(at 0 0 0)
			(layer "B.Fab")
			(effects
				(font
					(size 1.27 1.27)
				)
				(justify mirror)
			)
		)
		(duplicate_pad_numbers_are_jumpers no)
		(fp_line
			(start 0.7874 0.4064)
			(end 0.7874 -0.4064)
			(stroke
				(width 0.1524)
				(type default)
			)
			(layer "B.SilkS")
		)
		(fp_line
			(start 0.7874 -0.4064)
			(end -0.7874 -0.4064)
			(stroke
				(width 0.1524)
				(type default)
			)
			(layer "B.SilkS")
		)
		(fp_line
			(start -0.7874 0.4064)
			(end 0.7874 0.4064)
			(stroke
				(width 0.1524)
				(type default)
			)
			(layer "B.SilkS")
		)
		(fp_line
			(start -0.7874 -0.4064)
			(end -0.7874 0.4064)
			(stroke
				(width 0.1524)
				(type default)
			)
			(layer "B.SilkS")
		)
		(fp_line
			(start 0.67945 0.3048)
			(end 0.67945 -0.305054)
			(stroke
				(width 0.1)
				(type default)
			)
			(layer "B.Fab")
		)
		(fp_line
			(start 0.67945 -0.305054)
			(end 0.12065 -0.305054)
			(stroke
				(width 0.1)
				(type default)
			)
			(layer "B.Fab")
		)
		(fp_line
			(start 0.12065 0.3048)
			(end 0.67945 0.3048)
			(stroke
				(width 0.1)
				(type default)
			)
			(layer "B.Fab")
		)
		(fp_line
			(start 0.12065 0.2794)
			(end 0.12065 0.3048)
			(stroke
				(width 0.1)
				(type default)
			)
			(layer "B.Fab")
		)
		(fp_line
			(start 0.12065 -0.2794)
			(end -0.12065 -0.2794)
			(stroke
				(width 0.1)
				(type default)
			)
			(layer "B.Fab")
		)
		(fp_line
			(start 0.12065 -0.305054)
			(end 0.12065 -0.2794)
			(stroke
				(width 0.1)
				(type default)
			)
			(layer "B.Fab")
		)
		(fp_line
			(start -0.120396 0.3048)
			(end -0.120396 0.2794)
			(stroke
				(width 0.1)
				(type default)
			)
			(layer "B.Fab")
		)
		(fp_line
			(start -0.120396 0.2794)
			(end 0.12065 0.2794)
			(stroke
				(width 0.1)
				(type default)
			)
			(layer "B.Fab")
		)
		(fp_line
			(start -0.12065 -0.2794)
			(end -0.12065 -0.3048)
			(stroke
				(width 0.1)
				(type default)
			)
			(layer "B.Fab")
		)
		(fp_line
			(start -0.12065 -0.3048)
			(end -0.67945 -0.3048)
			(stroke
				(width 0.1)
				(type default)
			)
			(layer "B.Fab")
		)
		(fp_line
			(start -0.67945 0.3048)
			(end -0.120396 0.3048)
			(stroke
				(width 0.1)
				(type default)
			)
			(layer "B.Fab")
		)
		(fp_line
			(start -0.67945 -0.3048)
			(end -0.67945 0.3048)
			(stroke
				(width 0.1)
				(type default)
			)
			(layer "B.Fab")
		)
		(pad "1" smd circle
			(at 0.40005 0)
			(size 0 0)
			(layers "B.Cu" "B.Mask" "B.Paste")
			(net "I3C_SPD_DDRABCD_CPU1_LVC1_SCL_5")
		)
		(pad "2" smd circle
			(at -0.40005 0)
			(size 0 0)
			(layers "B.Cu" "B.Mask" "B.Paste")
			(net "I3C_SPD_DDRABCD_CPU1_LVC1_SCL")
		)
	)
	(footprint ""
		(layer "B.Cu")
		(at 355.397308 -252.176026 -90)
		(property "Reference" "C371"
			(at 0 0 90)
			(layer "B.SilkS")
			(hide yes)
			(effects
				(font
					(size 1.27 1.27)
				)
				(justify mirror)
			)
		)
		(property "Value" ""
			(at 0 0 90)
			(layer "B.Fab")
			(effects
				(font
					(size 1.27 1.27)
				)
				(justify mirror)
			)
		)
		(duplicate_pad_numbers_are_jumpers no)
		(fp_line
			(start -1.524 0.762)
			(end 1.524 0.762)
			(stroke
				(width 0.1524)
				(type default)
			)
			(layer "B.SilkS")
		)
		(fp_line
			(start 1.524 0.762)
			(end 1.524 -0.762)
			(stroke
				(width 0.1524)
				(type default)
			)
			(layer "B.SilkS")
		)
		(fp_line
			(start -1.524 -0.762)
			(end -1.524 0.762)
			(stroke
				(width 0.1524)
				(type default)
			)
			(layer "B.SilkS")
		)
		(fp_line
			(start 1.524 -0.762)
			(end -1.524 -0.762)
			(stroke
				(width 0.1524)
				(type default)
			)
			(layer "B.SilkS")
		)
		(fp_line
			(start -1.1049 0.724916)
			(end -1.1049 -0.724916)
			(stroke
				(width 0.1)
				(type default)
			)
			(layer "B.Fab")
		)
		(fp_line
			(start 1.1049 0.724916)
			(end -1.1049 0.724916)
			(stroke
				(width 0.1)
				(type default)
			)
			(layer "B.Fab")
		)
		(fp_line
			(start -1.1049 -0.724916)
			(end 1.1049 -0.724916)
			(stroke
				(width 0.1)
				(type default)
			)
			(layer "B.Fab")
		)
		(fp_line
			(start 1.1049 -0.724916)
			(end 1.1049 0.724916)
			(stroke
				(width 0.1)
				(type default)
			)
			(layer "B.Fab")
		)
		(pad "1" smd rect
			(at 0.889 0 270)
			(size 1.016 1.27)
			(layers "B.Cu" "B.Mask" "B.Paste")
			(net "PVCCIN_CPU0")
		)
		(pad "2" smd rect
			(at -0.889 0 270)
			(size 1.016 1.27)
			(layers "B.Cu" "B.Mask" "B.Paste")
			(net "GND")
		)
	)
)
